# S9S_MB_2U (Grand Teton) — schematic netlist excerpt (pin names and nets, part order shuffled) for the footprints in the layout excerpt that follows; sources: Cadence DE-HDL packaged netlist, KiCad conversion of 03242023_DA0F0TMBIJ0_F0T_Motherboard_J_brd_V01_OCP.brd

C983  Q_CAP  10UF 6.3V 20% X6S  pkg C0402  page 74 : A = PVCCIN_CPU0 ; B = GND
R3092  Q_RES  130 1% CHIP  pkg 0402LF  page 253 : A = LED_PWRGD_PVCCINFAON_CPU0 ; B = P3V3_AUX

(kicad_pcb
	(version 20260206)
	(generator "pcbnew")
	(generator_version "10.0")
	(general
		(thickness 1.6)
		(legacy_teardrops no)
	)
	(paper "A4")
	(title_block
		(title "03242023_DA0F0TMBIJ0_F0T_Motherboard_J_brd_V01_OCP.brd")
		(comment 1 "Grand Teton / footprints 709-710 of 6105")
	)
	(layers
		(0 "F.Cu" signal "TOP")
		(4 "In1.Cu" signal "GND")
		(6 "In2.Cu" signal "IN1")
		(8 "In3.Cu" signal "GND1")
		(10 "In4.Cu" signal "IN2")
		(12 "In5.Cu" signal "GND2")
		(14 "In6.Cu" signal "IN3")
		(16 "In7.Cu" signal "GND3")
		(18 "In8.Cu" signal "VCC")
		(20 "In9.Cu" signal "VCC1")
		(22 "In10.Cu" signal "GND4")
		(24 "In11.Cu" signal "IN4")
		(26 "In12.Cu" signal "GND5")
		(28 "In13.Cu" signal "IN5")
		(30 "In14.Cu" signal "GND6")
		(32 "In15.Cu" signal "IN6")
		(34 "In16.Cu" signal "GND7")
		(2 "B.Cu" signal "BOTTOM")
		(9 "F.Adhes" user "F.Adhesive")
		(11 "B.Adhes" user "B.Adhesive")
		(13 "F.Paste" user "Package Geometry/Pastemask Top")
		(15 "B.Paste" user "Package Geometry/Pastemask Bottom")
		(5 "F.SilkS" user "Ref Des/Silkscreen Top")
		(7 "B.SilkS" user "Ref Des/Silkscreen Bottom")
		(1 "F.Mask" user "Board Geometry/Soldermask Top")
		(3 "B.Mask" user "Board Geometry/Soldermask Bottom")
		(17 "Dwgs.User" user "User.Drawings")
		(19 "Cmts.User" user "User.Comments")
		(21 "Eco1.User" user "User.Eco1")
		(23 "Eco2.User" user "User.Eco2")
		(25 "Edge.Cuts" user "Board Geometry/Outline")
		(27 "Margin" user)
		(31 "F.CrtYd" user "Package Geometry/Place Bound Top")
		(29 "B.CrtYd" user "Package Geometry/Place Bound Bottom")
		(35 "F.Fab" user "Ref Des/Assembly Top")
		(33 "B.Fab" user "Ref Des/Assembly Bottom")
	)
	(footprint ""
		(layer "F.Cu")
		(at 353.254818 -245.634002 -90)
		(property "Reference" "C983"
			(at 0 0 270)
			(layer "F.SilkS")
			(hide yes)
			(effects
				(font
					(size 1.27 1.27)
				)
			)
		)
		(property "Value" ""
			(at 0 0 270)
			(layer "F.Fab")
			(effects
				(font
					(size 1.27 1.27)
				)
			)
		)
		(duplicate_pad_numbers_are_jumpers no)
		(fp_line
			(start -0.7874 0.4064)
			(end -0.7874 -0.4064)
			(stroke
				(width 0.1524)
				(type default)
			)
			(layer "F.SilkS")
		)
		(fp_line
			(start 0.7874 0.4064)
			(end -0.7874 0.4064)
			(stroke
				(width 0.1524)
				(type default)
			)
			(layer "F.SilkS")
		)
		(fp_line
			(start -0.7874 -0.4064)
			(end 0.7874 -0.4064)
			(stroke
				(width 0.1524)
				(type default)
			)
			(layer "F.SilkS")
		)
		(fp_line
			(start 0.7874 -0.4064)
			(end 0.7874 0.4064)
			(stroke
				(width 0.1524)
				(type default)
			)
			(layer "F.SilkS")
		)
		(fp_line
			(start -0.67945 0.3048)
			(end -0.67945 -0.305054)
			(stroke
				(width 0.1)
				(type default)
			)
			(layer "F.Fab")
		)
		(fp_line
			(start -0.12065 0.3048)
			(end -0.67945 0.3048)
			(stroke
				(width 0.1)
				(type default)
			)
			(layer "F.Fab")
		)
		(fp_line
			(start 0.120396 0.3048)
			(end 0.120396 0.2794)
			(stroke
				(width 0.1)
				(type default)
			)
			(layer "F.Fab")
		)
		(fp_line
			(start 0.67945 0.3048)
			(end 0.120396 0.3048)
			(stroke
				(width 0.1)
				(type default)
			)
			(layer "F.Fab")
		)
		(fp_line
			(start -0.12065 0.2794)
			(end -0.12065 0.3048)
			(stroke
				(width 0.1)
				(type default)
			)
			(layer "F.Fab")
		)
		(fp_line
			(start 0.120396 0.2794)
			(end -0.12065 0.2794)
			(stroke
				(width 0.1)
				(type default)
			)
			(layer "F.Fab")
		)
		(fp_line
			(start -0.12065 -0.2794)
			(end 0.12065 -0.2794)
			(stroke
				(width 0.1)
				(type default)
			)
			(layer "F.Fab")
		)
		(fp_line
			(start 0.12065 -0.2794)
			(end 0.12065 -0.3048)
			(stroke
				(width 0.1)
				(type default)
			)
			(layer "F.Fab")
		)
		(fp_line
			(start 0.12065 -0.3048)
			(end 0.67945 -0.3048)
			(stroke
				(width 0.1)
				(type default)
			)
			(layer "F.Fab")
		)
		(fp_line
			(start 0.67945 -0.3048)
			(end 0.67945 0.3048)
			(stroke
				(width 0.1)
				(type default)
			)
			(layer "F.Fab")
		)
		(fp_line
			(start -0.67945 -0.305054)
			(end -0.12065 -0.305054)
			(stroke
				(width 0.1)
				(type default)
			)
			(layer "F.Fab")
		)
		(fp_line
			(start -0.12065 -0.305054)
			(end -0.12065 -0.2794)
			(stroke
				(width 0.1)
				(type default)
			)
			(layer "F.Fab")
		)
		(pad "1" smd circle
			(at -0.40005 0 270)
			(size 0 0)
			(layers "F.Cu" "F.Mask" "F.Paste")
			(net "PVCCIN_CPU0")
		)
		(pad "2" smd circle
			(at 0.40005 0 270)
			(size 0 0)
			(layers "F.Cu" "F.Mask" "F.Paste")
			(net "GND")
		)
	)
	(footprint ""
		(layer "F.Cu")
		(at 56.618378 -81.345024 90)
		(property "Reference" "R3092"
			(at 0 0 90)
			(layer "F.SilkS")
			(hide yes)
			(effects
				(font
					(size 1.27 1.27)
				)
			)
		)
		(property "Value" ""
			(at 0 0 90)
			(layer "F.Fab")
			(effects
				(font
					(size 1.27 1.27)
				)
			)
		)
		(duplicate_pad_numbers_are_jumpers no)
		(fp_line
			(start 0.7874 -0.4064)
			(end 0.7874 0.4064)
			(stroke
				(width 0.1524)
				(type default)
			)
			(layer "F.SilkS")
		)
		(fp_line
			(start -0.7874 -0.4064)
			(end 0.7874 -0.4064)
			(stroke
				(width 0.1524)
				(type default)
			)
			(layer "F.SilkS")
		)
		(fp_line
			(start 0.7874 0.4064)
			(end -0.7874 0.4064)
			(stroke
				(width 0.1524)
				(type default)
			)
			(layer "F.SilkS")
		)
		(fp_line
			(start -0.7874 0.4064)
			(end -0.7874 -0.4064)
			(stroke
				(width 0.1524)
				(type default)
			)
			(layer "F.SilkS")
		)
		(fp_line
			(start -0.12065 -0.305054)
			(end -0.12065 -0.2794)
			(stroke
				(width 0.1)
				(type default)
			)
			(layer "F.Fab")
		)
		(fp_line
			(start -0.67945 -0.305054)
			(end -0.12065 -0.305054)
			(stroke
				(width 0.1)
				(type default)
			)
			(layer "F.Fab")
		)
		(fp_line
			(start 0.67945 -0.3048)
			(end 0.67945 0.3048)
			(stroke
				(width 0.1)
				(type default)
			)
			(layer "F.Fab")
		)
		(fp_line
			(start 0.12065 -0.3048)
			(end 0.67945 -0.3048)
			(stroke
				(width 0.1)
				(type default)
			)
			(layer "F.Fab")
		)
		(fp_line
			(start 0.12065 -0.2794)
			(end 0.12065 -0.3048)
			(stroke
				(width 0.1)
				(type default)
			)
			(layer "F.Fab")
		)
		(fp_line
			(start -0.12065 -0.2794)
			(end 0.12065 -0.2794)
			(stroke
				(width 0.1)
				(type default)
			)
			(layer "F.Fab")
		)
		(fp_line
			(start 0.120396 0.2794)
			(end -0.12065 0.2794)
			(stroke
				(width 0.1)
				(type default)
			)
			(layer "F.Fab")
		)
		(fp_line
			(start -0.12065 0.2794)
			(end -0.12065 0.3048)
			(stroke
				(width 0.1)
				(type default)
			)
			(layer "F.Fab")
		)
		(fp_line
			(start 0.67945 0.3048)
			(end 0.120396 0.3048)
			(stroke
				(width 0.1)
				(type default)
			)
			(layer "F.Fab")
		)
		(fp_line
			(start 0.120396 0.3048)
			(end 0.120396 0.2794)
			(stroke
				(width 0.1)
				(type default)
			)
			(layer "F.Fab")
		)
		(fp_line
			(start -0.12065 0.3048)
			(end -0.67945 0.3048)
			(stroke
				(width 0.1)
				(type default)
			)
			(layer "F.Fab")
		)
		(fp_line
			(start -0.67945 0.3048)
			(end -0.67945 -0.305054)
			(stroke
				(width 0.1)
				(type default)
			)
			(layer "F.Fab")
		)
		(pad "1" smd circle
			(at -0.40005 0 90)
			(size 0 0)
			(layers "F.Cu" "F.Mask" "F.Paste")
			(net "LED_PWRGD_PVCCINFAON_CPU0")
		)
		(pad "2" smd circle
			(at 0.40005 0 90)
			(size 0 0)
			(layers "F.Cu" "F.Mask" "F.Paste")
			(net "P3V3_AUX")
		)
	)
)
